(kicad_pcb
	(version 20260206)
	(generator "pcbnew")
	(generator_version "10.0")
	(general
		(thickness 1.6)
		(legacy_teardrops no)
	)
	(paper "A4")
	(title_block
		(title "15969-1a.1015WZS0858.brd")
		(comment 1 "Tioga Pass / footprints 210-217 of 295")
	)
	(layers
		(0 "F.Cu" signal "TOP")
		(4 "In1.Cu" signal "L2GND")
		(6 "In2.Cu" signal "L3")
		(8 "In3.Cu" signal "L4")
		(10 "In4.Cu" signal "L5GND")
		(2 "B.Cu" signal "BOTTOM")
		(9 "F.Adhes" user "F.Adhesive")
		(11 "B.Adhes" user "B.Adhesive")
		(13 "F.Paste" user "Package Geometry/Pastemask Top")
		(15 "B.Paste" user "Package Geometry/Pastemask Bottom")
		(5 "F.SilkS" user "Ref Des/Silkscreen Top")
		(7 "B.SilkS" user "Ref Des/Silkscreen Bottom")
		(1 "F.Mask" user "Board Geometry/Soldermask Top")
		(3 "B.Mask" user "Board Geometry/Soldermask Bottom")
		(17 "Dwgs.User" user "User.Drawings")
		(19 "Cmts.User" user "User.Comments")
		(21 "Eco1.User" user "User.Eco1")
		(23 "Eco2.User" user "User.Eco2")
		(25 "Edge.Cuts" user "Board Geometry/Outline")
		(27 "Margin" user)
		(31 "F.CrtYd" user "Package Geometry/Place Bound Top")
		(29 "B.CrtYd" user "Package Geometry/Place Bound Bottom")
		(35 "F.Fab" user "Ref Des/Assembly Top")
		(33 "B.Fab" user "Ref Des/Assembly Bottom")
	)
	(footprint ""
		(layer "B.Cu")
		(at 126.6952 -11.7094 180)
		(property "Reference" "R52"
			(at 0 0 0)
			(layer "B.SilkS")
			(hide yes)
			(effects
				(font
					(size 1.27 1.27)
				)
				(justify mirror)
			)
		)
		(property "Value" "10KR2F-2-GP"
			(at -0.064008 -3.993896 180)
			(unlocked yes)
			(layer "B.Fab")
			(hide yes)
			(effects
				(font
					(size 1.016 1.016)
					(thickness 0.1524)
				)
				(justify mirror)
			)
		)
		(property "Device Type" "R402H16"
			(at -0.064008 -5.517896 180)
			(unlocked yes)
			(layer "B.Fab")
			(hide yes)
			(effects
				(font
					(size 1.016 1.016)
					(thickness 0.1524)
				)
				(justify mirror)
			)
		)
		(duplicate_pad_numbers_are_jumpers no)
		(fp_line
			(start 0.508 -0.9398)
			(end 0.508 0.9398)
			(stroke
				(width 0.1524)
				(type default)
			)
			(layer "B.SilkS")
		)
		(fp_line
			(start -0.508 -0.9398)
			(end 0.508 -0.9398)
			(stroke
				(width 0.1524)
				(type default)
			)
			(layer "B.SilkS")
		)
		(fp_rect
			(start 0.508 0.9398)
			(end -0.508 -0.9398)
			(stroke
				(width 0)
				(type default)
			)
			(fill no)
			(layer "B.CrtYd")
		)
		(fp_rect
			(start 0.508 0.9398)
			(end -0.508 -0.9398)
			(stroke
				(width 0)
				(type default)
			)
			(fill no)
			(layer "B.Fab")
		)
		(pad "1" smd custom
			(at 0 -0.4445)
			(size 0.1397 0.1397)
			(layers "B.Cu" "B.Mask" "B.Paste")
			(net "SMB_P_HUB_A2")
			(options
				(clearance outline)
				(anchor circle)
			)
			(primitives
				(gr_poly
					(pts
						(arc
							(start -0.1778 0.2794)
							(mid -0.249642 0.249642)
							(end -0.2794 0.1778)
						)
						(arc
							(start -0.2794 -0.1778)
							(mid -0.249642 -0.249642)
							(end -0.1778 -0.2794)
						)
						(arc
							(start 0.1778 -0.2794)
							(mid 0.249642 -0.249642)
							(end 0.2794 -0.1778)
						)
						(arc
							(start 0.2794 0.1778)
							(mid 0.249642 0.249642)
							(end 0.1778 0.2794)
						)
					)
					(width 0)
					(fill yes)
				)
			)
		)
		(pad "2" smd custom
			(at 0 0.4445)
			(size 0.1397 0.1397)
			(layers "B.Cu" "B.Mask" "B.Paste")
			(net "GND")
			(options
				(clearance outline)
				(anchor circle)
			)
			(primitives
				(gr_poly
					(pts
						(arc
							(start -0.1778 0.2794)
							(mid -0.249642 0.249642)
							(end -0.2794 0.1778)
						)
						(arc
							(start -0.2794 -0.1778)
							(mid -0.249642 -0.249642)
							(end -0.1778 -0.2794)
						)
						(arc
							(start 0.1778 -0.2794)
							(mid 0.249642 -0.249642)
							(end 0.2794 -0.1778)
						)
						(arc
							(start 0.2794 0.1778)
							(mid 0.249642 0.249642)
							(end 0.1778 0.2794)
						)
					)
					(width 0)
					(fill yes)
				)
			)
		)
	)
	(footprint ""
		(layer "B.Cu")
		(at 102.2604 2.9718 180)
		(property "Reference" "R4"
			(at 0 0 0)
			(layer "B.SilkS")
			(hide yes)
			(effects
				(font
					(size 1.27 1.27)
				)
				(justify mirror)
			)
		)
		(property "Value" "4K7R2F-GP"
			(at -0.064008 -3.993896 180)
			(unlocked yes)
			(layer "B.Fab")
			(hide yes)
			(effects
				(font
					(size 1.016 1.016)
					(thickness 0.1524)
				)
				(justify mirror)
			)
		)
		(property "Device Type" "R402H16"
			(at -0.064008 -5.517896 180)
			(unlocked yes)
			(layer "B.Fab")
			(hide yes)
			(effects
				(font
					(size 1.016 1.016)
					(thickness 0.1524)
				)
				(justify mirror)
			)
		)
		(duplicate_pad_numbers_are_jumpers no)
		(fp_line
			(start 0.508 -0.9398)
			(end 0.508 0.9398)
			(stroke
				(width 0.1524)
				(type default)
			)
			(layer "B.SilkS")
		)
		(fp_line
			(start -0.508 -0.9398)
			(end 0.508 -0.9398)
			(stroke
				(width 0.1524)
				(type default)
			)
			(layer "B.SilkS")
		)
		(fp_rect
			(start 0.508 0.9398)
			(end -0.508 -0.9398)
			(stroke
				(width 0)
				(type default)
			)
			(fill no)
			(layer "B.CrtYd")
		)
		(fp_rect
			(start 0.508 0.9398)
			(end -0.508 -0.9398)
			(stroke
				(width 0)
				(type default)
			)
			(fill no)
			(layer "B.Fab")
		)
		(pad "1" smd custom
			(at 0 -0.4445)
			(size 0.1397 0.1397)
			(layers "B.Cu" "B.Mask" "B.Paste")
			(net "P3V3_STBY")
			(options
				(clearance outline)
				(anchor circle)
			)
			(primitives
				(gr_poly
					(pts
						(arc
							(start -0.1778 0.2794)
							(mid -0.249642 0.249642)
							(end -0.2794 0.1778)
						)
						(arc
							(start -0.2794 -0.1778)
							(mid -0.249642 -0.249642)
							(end -0.1778 -0.2794)
						)
						(arc
							(start 0.1778 -0.2794)
							(mid 0.249642 -0.249642)
							(end 0.2794 -0.1778)
						)
						(arc
							(start 0.2794 0.1778)
							(mid 0.249642 0.249642)
							(end 0.1778 0.2794)
						)
					)
					(width 0)
					(fill yes)
				)
			)
		)
		(pad "2" smd custom
			(at 0 0.4445)
			(size 0.1397 0.1397)
			(layers "B.Cu" "B.Mask" "B.Paste")
			(net "SMDAT_BMC_SLOT2")
			(options
				(clearance outline)
				(anchor circle)
			)
			(primitives
				(gr_poly
					(pts
						(arc
							(start -0.1778 0.2794)
							(mid -0.249642 0.249642)
							(end -0.2794 0.1778)
						)
						(arc
							(start -0.2794 -0.1778)
							(mid -0.249642 -0.249642)
							(end -0.1778 -0.2794)
						)
						(arc
							(start 0.1778 -0.2794)
							(mid 0.249642 -0.249642)
							(end 0.2794 -0.1778)
						)
						(arc
							(start 0.2794 0.1778)
							(mid 0.249642 0.249642)
							(end 0.1778 0.2794)
						)
					)
					(width 0)
					(fill yes)
				)
			)
		)
	)
	(footprint ""
		(layer "B.Cu")
		(at 125.857 -26.6954 180)
		(property "Reference" "RU25"
			(at 0 0 0)
			(layer "B.SilkS")
			(hide yes)
			(effects
				(font
					(size 1.27 1.27)
				)
				(justify mirror)
			)
		)
		(property "Value" "100KR2F-L1-GP"
			(at -0.064008 -3.993896 180)
			(unlocked yes)
			(layer "B.Fab")
			(hide yes)
			(effects
				(font
					(size 1.016 1.016)
					(thickness 0.1524)
				)
				(justify mirror)
			)
		)
		(property "Device Type" "R402H16"
			(at -0.064008 -5.517896 180)
			(unlocked yes)
			(layer "B.Fab")
			(hide yes)
			(effects
				(font
					(size 1.016 1.016)
					(thickness 0.1524)
				)
				(justify mirror)
			)
		)
		(duplicate_pad_numbers_are_jumpers no)
		(fp_line
			(start 0.508 -0.9398)
			(end 0.508 0.9398)
			(stroke
				(width 0.1524)
				(type default)
			)
			(layer "B.SilkS")
		)
		(fp_line
			(start -0.508 -0.9398)
			(end 0.508 -0.9398)
			(stroke
				(width 0.1524)
				(type default)
			)
			(layer "B.SilkS")
		)
		(fp_rect
			(start 0.508 0.9398)
			(end -0.508 -0.9398)
			(stroke
				(width 0)
				(type default)
			)
			(fill no)
			(layer "B.CrtYd")
		)
		(fp_rect
			(start 0.508 0.9398)
			(end -0.508 -0.9398)
			(stroke
				(width 0)
				(type default)
			)
			(fill no)
			(layer "B.Fab")
		)
		(pad "1" smd custom
			(at 0 -0.4445)
			(size 0.1397 0.1397)
			(layers "B.Cu" "B.Mask" "B.Paste")
			(net "CFG_SEL1")
			(options
				(clearance outline)
				(anchor circle)
			)
			(primitives
				(gr_poly
					(pts
						(arc
							(start -0.1778 0.2794)
							(mid -0.249642 0.249642)
							(end -0.2794 0.1778)
						)
						(arc
							(start -0.2794 -0.1778)
							(mid -0.249642 -0.249642)
							(end -0.1778 -0.2794)
						)
						(arc
							(start 0.1778 -0.2794)
							(mid 0.249642 -0.249642)
							(end 0.2794 -0.1778)
						)
						(arc
							(start 0.2794 0.1778)
							(mid 0.249642 0.249642)
							(end 0.1778 0.2794)
						)
					)
					(width 0)
					(fill yes)
				)
			)
		)
		(pad "2" smd custom
			(at 0 0.4445)
			(size 0.1397 0.1397)
			(layers "B.Cu" "B.Mask" "B.Paste")
			(net "GND")
			(options
				(clearance outline)
				(anchor circle)
			)
			(primitives
				(gr_poly
					(pts
						(arc
							(start -0.1778 0.2794)
							(mid -0.249642 0.249642)
							(end -0.2794 0.1778)
						)
						(arc
							(start -0.2794 -0.1778)
							(mid -0.249642 -0.249642)
							(end -0.1778 -0.2794)
						)
						(arc
							(start 0.1778 -0.2794)
							(mid 0.249642 -0.249642)
							(end 0.2794 -0.1778)
						)
						(arc
							(start 0.2794 0.1778)
							(mid 0.249642 0.249642)
							(end 0.1778 0.2794)
						)
					)
					(width 0)
					(fill yes)
				)
			)
		)
	)
	(footprint ""
		(layer "B.Cu")
		(at 103.886 -0.1778 180)
		(property "Reference" "R6"
			(at 0 0 0)
			(layer "B.SilkS")
			(hide yes)
			(effects
				(font
					(size 1.27 1.27)
				)
				(justify mirror)
			)
		)
		(property "Value" "4K7R2F-GP"
			(at -0.064008 -3.993896 180)
			(unlocked yes)
			(layer "B.Fab")
			(hide yes)
			(effects
				(font
					(size 1.016 1.016)
					(thickness 0.1524)
				)
				(justify mirror)
			)
		)
		(property "Device Type" "R402H16"
			(at -0.064008 -5.517896 180)
			(unlocked yes)
			(layer "B.Fab")
			(hide yes)
			(effects
				(font
					(size 1.016 1.016)
					(thickness 0.1524)
				)
				(justify mirror)
			)
		)
		(duplicate_pad_numbers_are_jumpers no)
		(fp_line
			(start 0.508 -0.9398)
			(end 0.508 0.9398)
			(stroke
				(width 0.1524)
				(type default)
			)
			(layer "B.SilkS")
		)
		(fp_line
			(start -0.508 -0.9398)
			(end 0.508 -0.9398)
			(stroke
				(width 0.1524)
				(type default)
			)
			(layer "B.SilkS")
		)
		(fp_rect
			(start 0.508 0.9398)
			(end -0.508 -0.9398)
			(stroke
				(width 0)
				(type default)
			)
			(fill no)
			(layer "B.CrtYd")
		)
		(fp_rect
			(start 0.508 0.9398)
			(end -0.508 -0.9398)
			(stroke
				(width 0)
				(type default)
			)
			(fill no)
			(layer "B.Fab")
		)
		(pad "1" smd custom
			(at 0 -0.4445)
			(size 0.1397 0.1397)
			(layers "B.Cu" "B.Mask" "B.Paste")
			(net "P3V3_STBY")
			(options
				(clearance outline)
				(anchor circle)
			)
			(primitives
				(gr_poly
					(pts
						(arc
							(start -0.1778 0.2794)
							(mid -0.249642 0.249642)
							(end -0.2794 0.1778)
						)
						(arc
							(start -0.2794 -0.1778)
							(mid -0.249642 -0.249642)
							(end -0.1778 -0.2794)
						)
						(arc
							(start 0.1778 -0.2794)
							(mid 0.249642 -0.249642)
							(end 0.2794 -0.1778)
						)
						(arc
							(start 0.2794 0.1778)
							(mid 0.249642 0.249642)
							(end 0.1778 0.2794)
						)
					)
					(width 0)
					(fill yes)
				)
			)
		)
		(pad "2" smd custom
			(at 0 0.4445)
			(size 0.1397 0.1397)
			(layers "B.Cu" "B.Mask" "B.Paste")
			(net "SMDAT_BMC_SLOT3")
			(options
				(clearance outline)
				(anchor circle)
			)
			(primitives
				(gr_poly
					(pts
						(arc
							(start -0.1778 0.2794)
							(mid -0.249642 0.249642)
							(end -0.2794 0.1778)
						)
						(arc
							(start -0.2794 -0.1778)
							(mid -0.249642 -0.249642)
							(end -0.1778 -0.2794)
						)
						(arc
							(start 0.1778 -0.2794)
							(mid 0.249642 -0.249642)
							(end 0.2794 -0.1778)
						)
						(arc
							(start 0.2794 0.1778)
							(mid 0.249642 0.249642)
							(end 0.1778 0.2794)
						)
					)
					(width 0)
					(fill yes)
				)
			)
		)
	)
	(footprint ""
		(layer "B.Cu")
		(at 131.826 -6.3246 180)
		(property "Reference" "R166"
			(at 0 0 0)
			(layer "B.SilkS")
			(hide yes)
			(effects
				(font
					(size 1.27 1.27)
				)
				(justify mirror)
			)
		)
		(property "Value" "0R2F-1-GP"
			(at -0.064008 -3.993896 180)
			(unlocked yes)
			(layer "B.Fab")
			(hide yes)
			(effects
				(font
					(size 1.016 1.016)
					(thickness 0.1524)
				)
				(justify mirror)
			)
		)
		(property "Device Type" "R402H16"
			(at -0.064008 -5.517896 180)
			(unlocked yes)
			(layer "B.Fab")
			(hide yes)
			(effects
				(font
					(size 1.016 1.016)
					(thickness 0.1524)
				)
				(justify mirror)
			)
		)
		(duplicate_pad_numbers_are_jumpers no)
		(fp_line
			(start 0.508 -0.9398)
			(end 0.508 0.9398)
			(stroke
				(width 0.1524)
				(type default)
			)
			(layer "B.SilkS")
		)
		(fp_line
			(start -0.508 -0.9398)
			(end 0.508 -0.9398)
			(stroke
				(width 0.1524)
				(type default)
			)
			(layer "B.SilkS")
		)
		(fp_rect
			(start 0.508 0.9398)
			(end -0.508 -0.9398)
			(stroke
				(width 0)
				(type default)
			)
			(fill no)
			(layer "B.CrtYd")
		)
		(fp_rect
			(start 0.508 0.9398)
			(end -0.508 -0.9398)
			(stroke
				(width 0)
				(type default)
			)
			(fill no)
			(layer "B.Fab")
		)
		(pad "1" smd custom
			(at 0 -0.4445)
			(size 0.1397 0.1397)
			(layers "B.Cu" "B.Mask" "B.Paste")
			(net "SMB_PCH_DEVICE_ALERT_N")
			(options
				(clearance outline)
				(anchor circle)
			)
			(primitives
				(gr_poly
					(pts
						(arc
							(start -0.1778 0.2794)
							(mid -0.249642 0.249642)
							(end -0.2794 0.1778)
						)
						(arc
							(start -0.2794 -0.1778)
							(mid -0.249642 -0.249642)
							(end -0.1778 -0.2794)
						)
						(arc
							(start 0.1778 -0.2794)
							(mid 0.249642 -0.249642)
							(end 0.2794 -0.1778)
						)
						(arc
							(start 0.2794 0.1778)
							(mid 0.249642 0.249642)
							(end 0.1778 0.2794)
						)
					)
					(width 0)
					(fill yes)
				)
			)
		)
		(pad "2" smd custom
			(at 0 0.4445)
			(size 0.1397 0.1397)
			(layers "B.Cu" "B.Mask" "B.Paste")
			(net "GPIO_P_EXP_INT_N")
			(options
				(clearance outline)
				(anchor circle)
			)
			(primitives
				(gr_poly
					(pts
						(arc
							(start -0.1778 0.2794)
							(mid -0.249642 0.249642)
							(end -0.2794 0.1778)
						)
						(arc
							(start -0.2794 -0.1778)
							(mid -0.249642 -0.249642)
							(end -0.1778 -0.2794)
						)
						(arc
							(start 0.1778 -0.2794)
							(mid 0.249642 -0.249642)
							(end 0.2794 -0.1778)
						)
						(arc
							(start 0.2794 0.1778)
							(mid 0.249642 0.249642)
							(end 0.1778 0.2794)
						)
					)
					(width 0)
					(fill yes)
				)
			)
		)
	)
	(footprint ""
		(layer "B.Cu")
		(at 44.42206 -1.31826 -90)
		(property "Reference" "R36"
			(at 0 0 90)
			(layer "B.SilkS")
			(hide yes)
			(effects
				(font
					(size 1.27 1.27)
				)
				(justify mirror)
			)
		)
		(property "Value" "0R2F-1-GP"
			(at -0.064008 -3.993896 270)
			(unlocked yes)
			(layer "B.Fab")
			(hide yes)
			(effects
				(font
					(size 1.016 1.016)
					(thickness 0.1524)
				)
				(justify mirror)
			)
		)
		(property "Device Type" "R402H16"
			(at -0.064008 -5.517896 270)
			(unlocked yes)
			(layer "B.Fab")
			(hide yes)
			(effects
				(font
					(size 1.016 1.016)
					(thickness 0.1524)
				)
				(justify mirror)
			)
		)
		(duplicate_pad_numbers_are_jumpers no)
		(fp_line
			(start -0.508 -0.9398)
			(end 0.508 -0.9398)
			(stroke
				(width 0.1524)
				(type default)
			)
			(layer "B.SilkS")
		)
		(fp_line
			(start 0.508 -0.9398)
			(end 0.508 0.9398)
			(stroke
				(width 0.1524)
				(type default)
			)
			(layer "B.SilkS")
		)
		(fp_rect
			(start 0.508 0.9398)
			(end -0.508 -0.9398)
			(stroke
				(width 0)
				(type default)
			)
			(fill no)
			(layer "B.CrtYd")
		)
		(fp_rect
			(start 0.508 0.9398)
			(end -0.508 -0.9398)
			(stroke
				(width 0)
				(type default)
			)
			(fill no)
			(layer "B.Fab")
		)
		(pad "1" smd custom
			(at 0 -0.4445 90)
			(size 0.1397 0.1397)
			(layers "B.Cu" "B.Mask" "B.Paste")
			(net "SMCLK_PCH_SLOT2")
			(options
				(clearance outline)
				(anchor circle)
			)
			(primitives
				(gr_poly
					(pts
						(arc
							(start -0.1778 0.2794)
							(mid -0.249642 0.249642)
							(end -0.2794 0.1778)
						)
						(arc
							(start -0.2794 -0.1778)
							(mid -0.249642 -0.249642)
							(end -0.1778 -0.2794)
						)
						(arc
							(start 0.1778 -0.2794)
							(mid 0.249642 -0.249642)
							(end 0.2794 -0.1778)
						)
						(arc
							(start 0.2794 0.1778)
							(mid 0.249642 0.249642)
							(end 0.1778 0.2794)
						)
					)
					(width 0)
					(fill yes)
				)
			)
		)
		(pad "2" smd custom
			(at 0 0.4445 90)
			(size 0.1397 0.1397)
			(layers "B.Cu" "B.Mask" "B.Paste")
			(net "SMCLK_PCH_SLOT2_R")
			(options
				(clearance outline)
				(anchor circle)
			)
			(primitives
				(gr_poly
					(pts
						(arc
							(start -0.1778 0.2794)
							(mid -0.249642 0.249642)
							(end -0.2794 0.1778)
						)
						(arc
							(start -0.2794 -0.1778)
							(mid -0.249642 -0.249642)
							(end -0.1778 -0.2794)
						)
						(arc
							(start 0.1778 -0.2794)
							(mid 0.249642 -0.249642)
							(end 0.2794 -0.1778)
						)
						(arc
							(start 0.2794 0.1778)
							(mid 0.249642 0.249642)
							(end 0.1778 0.2794)
						)
					)
					(width 0)
					(fill yes)
				)
			)
		)
	)
	(footprint ""
		(layer "B.Cu")
		(at 38.8366 -1.5113 90)
		(property "Reference" "C24"
			(at 0 0 90)
			(layer "B.SilkS")
			(hide yes)
			(effects
				(font
					(size 1.27 1.27)
				)
				(justify mirror)
			)
		)
		(property "Value" "SCD1U16V2KX-3GP"
			(at -1.1811 -2.7051 90)
			(unlocked yes)
			(layer "B.Fab")
			(hide yes)
			(effects
				(font
					(size 1.016 1.016)
					(thickness 0.1524)
				)
				(justify mirror)
			)
		)
		(property "Device Type" "C402H22"
			(at -1.1811 -4.2291 90)
			(unlocked yes)
			(layer "B.Fab")
			(hide yes)
			(effects
				(font
					(size 1.016 1.016)
					(thickness 0.1524)
				)
				(justify mirror)
			)
		)
		(duplicate_pad_numbers_are_jumpers no)
		(fp_rect
			(start 0.4318 0.9525)
			(end -0.4318 -0.9525)
			(stroke
				(width 0)
				(type default)
			)
			(fill no)
			(layer "B.CrtYd")
		)
		(fp_rect
			(start 0.4318 0.9525)
			(end -0.4318 -0.9525)
			(stroke
				(width 0)
				(type default)
			)
			(fill no)
			(layer "B.Fab")
		)
		(pad "1" smd custom
			(at 0 -0.4445 270)
			(size 0.1524 0.1524)
			(layers "B.Cu" "B.Mask" "B.Paste")
			(net "P3V3")
			(options
				(clearance outline)
				(anchor circle)
			)
			(primitives
				(gr_poly
					(pts
						(arc
							(start 0.3048 0.2032)
							(mid 0.275042 0.275042)
							(end 0.2032 0.3048)
						)
						(arc
							(start -0.2032 0.3048)
							(mid -0.275042 0.275042)
							(end -0.3048 0.2032)
						)
						(arc
							(start -0.3048 -0.2032)
							(mid -0.275042 -0.275042)
							(end -0.2032 -0.3048)
						)
						(arc
							(start 0.2032 -0.3048)
							(mid 0.275042 -0.275042)
							(end 0.3048 -0.2032)
						)
					)
					(width 0)
					(fill yes)
				)
			)
		)
		(pad "2" smd custom
			(at 0 0.4445 270)
			(size 0.1524 0.1524)
			(layers "B.Cu" "B.Mask" "B.Paste")
			(net "GND")
			(options
				(clearance outline)
				(anchor circle)
			)
			(primitives
				(gr_poly
					(pts
						(arc
							(start 0.3048 0.2032)
							(mid 0.275042 0.275042)
							(end 0.2032 0.3048)
						)
						(arc
							(start -0.2032 0.3048)
							(mid -0.275042 0.275042)
							(end -0.3048 0.2032)
						)
						(arc
							(start -0.3048 -0.2032)
							(mid -0.275042 -0.275042)
							(end -0.2032 -0.3048)
						)
						(arc
							(start 0.2032 -0.3048)
							(mid 0.275042 -0.275042)
							(end 0.3048 -0.2032)
						)
					)
					(width 0)
					(fill yes)
				)
			)
		)
	)
	(footprint ""
		(layer "B.Cu")
		(at 121.9962 -26.3017)
		(property "Reference" "TP83"
			(at 0 0 0)
			(layer "B.SilkS")
			(hide yes)
			(effects
				(font
					(size 1.27 1.27)
				)
				(justify mirror)
			)
		)
		(property "Value" "TPAD24"
			(at 0 -1.6129 0)
			(unlocked yes)
			(layer "B.Fab")
			(hide yes)
			(effects
				(font
					(size 1.016 1.016)
					(thickness 0.1524)
				)
				(justify mirror)
			)
		)
		(property "Device Type" "TPAD24"
			(at 0 -3.1369 0)
			(unlocked yes)
			(layer "B.Fab")
			(hide yes)
			(effects
				(font
					(size 1.016 1.016)
					(thickness 0.1524)
				)
				(justify mirror)
			)
		)
		(duplicate_pad_numbers_are_jumpers no)
		(fp_poly
			(pts
				(arc
					(start 0.3048 0)
					(mid -0.3048 0)
					(end 0.3048 0)
				)
			)
			(stroke
				(width 0)
				(type default)
			)
			(fill no)
			(layer "B.CrtYd")
		)
		(fp_poly
			(pts
				(arc
					(start 0.6096 0)
					(mid -0.6096 0)
					(end 0.6096 0)
				)
			)
			(stroke
				(width 0)
				(type default)
			)
			(fill no)
			(layer "B.Fab")
		)
		(pad "1" smd circle
			(at 0 0 180)
			(size 0.6096 0.6096)
			(layers "B.Cu" "B.Mask" "B.Paste")
			(net "TP_USB_OCS_N3")
		)
	)
)
